# T6G (Grand Teton) — schematic netlist excerpt (pin names and nets, part order shuffled) for the footprints in the layout excerpt that follows; sources: Cadence DE-HDL packaged netlist, KiCad conversion of 04192023_DAF0TMB3IC0_F0TG_MB_C_brd_V02_OCP.brd

R1407  Q_RES  4.7K 5% CHIP  pkg 0201LF  page 185 : A = P1V8_CPU1_RT_1D ; B = SMB_RT_CPU1_P2_ROM_MUX_2D_R_SCL
PR236  Q_RES  0 5% CHIP  pkg 0402LF  page 54 : A = SVID_PVDDCR_CPU1_P1_SVC_R ; B = SVID_PVDDCR_CPU1_P1_SVC
C2341  Q_CAP  22UF 4V 20% X6S  pkg C0402  page 73 : A = PVDDCR_CPU0_P1 ; B = GND

(kicad_pcb
	(version 20260206)
	(generator "pcbnew")
	(generator_version "10.0")
	(general
		(thickness 1.6)
		(legacy_teardrops no)
	)
	(paper "A4")
	(title_block
		(title "04192023_DAF0TMB3IC0_F0TG_MB_C_brd_V02_OCP.brd")
		(comment 1 "Grand Teton / footprints 6425-6427 of 8354")
	)
	(layers
		(0 "F.Cu" signal "TOP")
		(4 "In1.Cu" signal "GND")
		(6 "In2.Cu" signal "IN1")
		(8 "In3.Cu" signal "GND1")
		(10 "In4.Cu" signal "IN2")
		(12 "In5.Cu" signal "GND2")
		(14 "In6.Cu" signal "IN3")
		(16 "In7.Cu" signal "GND3")
		(18 "In8.Cu" signal "VCC")
		(20 "In9.Cu" signal "VCC1")
		(22 "In10.Cu" signal "GND4")
		(24 "In11.Cu" signal "IN4")
		(26 "In12.Cu" signal "GND5")
		(28 "In13.Cu" signal "IN5")
		(30 "In14.Cu" signal "GND6")
		(32 "In15.Cu" signal "IN6")
		(34 "In16.Cu" signal "GND7")
		(2 "B.Cu" signal "BOTTOM")
		(9 "F.Adhes" user "F.Adhesive")
		(11 "B.Adhes" user "B.Adhesive")
		(13 "F.Paste" user "Package Geometry/Pastemask Top")
		(15 "B.Paste" user "Package Geometry/Pastemask Bottom")
		(5 "F.SilkS" user "Ref Des/Silkscreen Top")
		(7 "B.SilkS" user "Ref Des/Silkscreen Bottom")
		(1 "F.Mask" user "Board Geometry/Soldermask Top")
		(3 "B.Mask" user "Board Geometry/Soldermask Bottom")
		(17 "Dwgs.User" user "User.Drawings")
		(19 "Cmts.User" user "User.Comments")
		(21 "Eco1.User" user "User.Eco1")
		(23 "Eco2.User" user "User.Eco2")
		(25 "Edge.Cuts" user "Board Geometry/Outline")
		(27 "Margin" user)
		(31 "F.CrtYd" user "Package Geometry/Place Bound Top")
		(29 "B.CrtYd" user "Package Geometry/Place Bound Bottom")
		(35 "F.Fab" user "Ref Des/Assembly Top")
		(33 "B.Fab" user "Ref Des/Assembly Bottom")
	)
	(footprint ""
		(layer "B.Cu")
		(at 91.762834 -308.606952 90)
		(property "Reference" "PR236"
			(at 0 0 90)
			(layer "B.SilkS")
			(hide yes)
			(effects
				(font
					(size 1.27 1.27)
				)
				(justify mirror)
			)
		)
		(property "Value" ""
			(at 0 0 90)
			(layer "B.Fab")
			(effects
				(font
					(size 1.27 1.27)
				)
				(justify mirror)
			)
		)
		(duplicate_pad_numbers_are_jumpers no)
		(fp_line
			(start 0.7874 -0.4064)
			(end -0.7874 -0.4064)
			(stroke
				(width 0.1524)
				(type default)
			)
			(layer "B.SilkS")
		)
		(fp_line
			(start -0.7874 -0.4064)
			(end -0.7874 0.4064)
			(stroke
				(width 0.1524)
				(type default)
			)
			(layer "B.SilkS")
		)
		(fp_line
			(start 0.7874 0.4064)
			(end 0.7874 -0.4064)
			(stroke
				(width 0.1524)
				(type default)
			)
			(layer "B.SilkS")
		)
		(fp_line
			(start -0.7874 0.4064)
			(end 0.7874 0.4064)
			(stroke
				(width 0.1524)
				(type default)
			)
			(layer "B.SilkS")
		)
		(fp_line
			(start 0.67945 -0.305054)
			(end 0.12065 -0.305054)
			(stroke
				(width 0.1)
				(type default)
			)
			(layer "B.Fab")
		)
		(fp_line
			(start 0.12065 -0.305054)
			(end 0.12065 -0.2794)
			(stroke
				(width 0.1)
				(type default)
			)
			(layer "B.Fab")
		)
		(fp_line
			(start -0.12065 -0.3048)
			(end -0.67945 -0.3048)
			(stroke
				(width 0.1)
				(type default)
			)
			(layer "B.Fab")
		)
		(fp_line
			(start -0.67945 -0.3048)
			(end -0.67945 0.3048)
			(stroke
				(width 0.1)
				(type default)
			)
			(layer "B.Fab")
		)
		(fp_line
			(start 0.12065 -0.2794)
			(end -0.12065 -0.2794)
			(stroke
				(width 0.1)
				(type default)
			)
			(layer "B.Fab")
		)
		(fp_line
			(start -0.12065 -0.2794)
			(end -0.12065 -0.3048)
			(stroke
				(width 0.1)
				(type default)
			)
			(layer "B.Fab")
		)
		(fp_line
			(start 0.12065 0.2794)
			(end 0.12065 0.3048)
			(stroke
				(width 0.1)
				(type default)
			)
			(layer "B.Fab")
		)
		(fp_line
			(start -0.120396 0.2794)
			(end 0.12065 0.2794)
			(stroke
				(width 0.1)
				(type default)
			)
			(layer "B.Fab")
		)
		(fp_line
			(start 0.67945 0.3048)
			(end 0.67945 -0.305054)
			(stroke
				(width 0.1)
				(type default)
			)
			(layer "B.Fab")
		)
		(fp_line
			(start 0.12065 0.3048)
			(end 0.67945 0.3048)
			(stroke
				(width 0.1)
				(type default)
			)
			(layer "B.Fab")
		)
		(fp_line
			(start -0.120396 0.3048)
			(end -0.120396 0.2794)
			(stroke
				(width 0.1)
				(type default)
			)
			(layer "B.Fab")
		)
		(fp_line
			(start -0.67945 0.3048)
			(end -0.120396 0.3048)
			(stroke
				(width 0.1)
				(type default)
			)
			(layer "B.Fab")
		)
		(pad "1" smd circle
			(at 0.40005 0 270)
			(size 0 0)
			(layers "B.Cu" "B.Mask" "B.Paste")
			(net "SVID_PVDDCR_CPU1_P1_SVC_R")
		)
		(pad "2" smd circle
			(at -0.40005 0 270)
			(size 0 0)
			(layers "B.Cu" "B.Mask" "B.Paste")
			(net "SVID_PVDDCR_CPU1_P1_SVC")
		)
	)
	(footprint ""
		(layer "B.Cu")
		(at 111.800386 -247.971564 90)
		(property "Reference" "C2341"
			(at 0 0 90)
			(layer "B.SilkS")
			(hide yes)
			(effects
				(font
					(size 1.27 1.27)
				)
				(justify mirror)
			)
		)
		(property "Value" ""
			(at 0 0 90)
			(layer "B.Fab")
			(effects
				(font
					(size 1.27 1.27)
				)
				(justify mirror)
			)
		)
		(duplicate_pad_numbers_are_jumpers no)
		(fp_line
			(start 0.7874 -0.4064)
			(end -0.7874 -0.4064)
			(stroke
				(width 0.1524)
				(type default)
			)
			(layer "B.SilkS")
		)
		(fp_line
			(start -0.7874 -0.4064)
			(end -0.7874 0.4064)
			(stroke
				(width 0.1524)
				(type default)
			)
			(layer "B.SilkS")
		)
		(fp_line
			(start 0.7874 0.4064)
			(end 0.7874 -0.4064)
			(stroke
				(width 0.1524)
				(type default)
			)
			(layer "B.SilkS")
		)
		(fp_line
			(start -0.7874 0.4064)
			(end 0.7874 0.4064)
			(stroke
				(width 0.1524)
				(type default)
			)
			(layer "B.SilkS")
		)
		(fp_line
			(start 0.67945 -0.305054)
			(end 0.12065 -0.305054)
			(stroke
				(width 0.1)
				(type default)
			)
			(layer "B.Fab")
		)
		(fp_line
			(start 0.12065 -0.305054)
			(end 0.12065 -0.2794)
			(stroke
				(width 0.1)
				(type default)
			)
			(layer "B.Fab")
		)
		(fp_line
			(start -0.12065 -0.3048)
			(end -0.67945 -0.3048)
			(stroke
				(width 0.1)
				(type default)
			)
			(layer "B.Fab")
		)
		(fp_line
			(start -0.67945 -0.3048)
			(end -0.67945 0.3048)
			(stroke
				(width 0.1)
				(type default)
			)
			(layer "B.Fab")
		)
		(fp_line
			(start 0.12065 -0.2794)
			(end -0.12065 -0.2794)
			(stroke
				(width 0.1)
				(type default)
			)
			(layer "B.Fab")
		)
		(fp_line
			(start -0.12065 -0.2794)
			(end -0.12065 -0.3048)
			(stroke
				(width 0.1)
				(type default)
			)
			(layer "B.Fab")
		)
		(fp_line
			(start 0.12065 0.2794)
			(end 0.12065 0.3048)
			(stroke
				(width 0.1)
				(type default)
			)
			(layer "B.Fab")
		)
		(fp_line
			(start -0.120396 0.2794)
			(end 0.12065 0.2794)
			(stroke
				(width 0.1)
				(type default)
			)
			(layer "B.Fab")
		)
		(fp_line
			(start 0.67945 0.3048)
			(end 0.67945 -0.305054)
			(stroke
				(width 0.1)
				(type default)
			)
			(layer "B.Fab")
		)
		(fp_line
			(start 0.12065 0.3048)
			(end 0.67945 0.3048)
			(stroke
				(width 0.1)
				(type default)
			)
			(layer "B.Fab")
		)
		(fp_line
			(start -0.120396 0.3048)
			(end -0.120396 0.2794)
			(stroke
				(width 0.1)
				(type default)
			)
			(layer "B.Fab")
		)
		(fp_line
			(start -0.67945 0.3048)
			(end -0.120396 0.3048)
			(stroke
				(width 0.1)
				(type default)
			)
			(layer "B.Fab")
		)
		(pad "1" smd circle
			(at 0.40005 0 270)
			(size 0 0)
			(layers "B.Cu" "B.Mask" "B.Paste")
			(net "PVDDCR_CPU0_P1")
		)
		(pad "2" smd circle
			(at -0.40005 0 270)
			(size 0 0)
			(layers "B.Cu" "B.Mask" "B.Paste")
			(net "GND")
		)
	)
	(footprint ""
		(layer "B.Cu")
		(at 239.903 -341.884)
		(property "Reference" "R1407"
			(at 0 0 0)
			(layer "B.SilkS")
			(hide yes)
			(effects
				(font
					(size 1.27 1.27)
				)
				(justify mirror)
			)
		)
		(property "Value" ""
			(at 0 0 0)
			(layer "B.Fab")
			(effects
				(font
					(size 1.27 1.27)
				)
				(justify mirror)
			)
		)
		(duplicate_pad_numbers_are_jumpers no)
		(fp_line
			(start -0.32512 -0.175006)
			(end -0.32512 0.175006)
			(stroke
				(width 0.1)
				(type default)
			)
			(layer "B.Fab")
		)
		(fp_line
			(start -0.32512 0.175006)
			(end 0.32512 0.175006)
			(stroke
				(width 0.1)
				(type default)
			)
			(layer "B.Fab")
		)
		(fp_line
			(start 0.32512 -0.175006)
			(end -0.32512 -0.175006)
			(stroke
				(width 0.1)
				(type default)
			)
			(layer "B.Fab")
		)
		(fp_line
			(start 0.32512 0.175006)
			(end 0.32512 -0.175006)
			(stroke
				(width 0.1)
				(type default)
			)
			(layer "B.Fab")
		)
		(pad "1" smd rect
			(at 0.2667 0 180)
			(size 0.3048 0.381)
			(layers "B.Cu" "B.Mask" "B.Paste")
			(net "P1V8_CPU1_RT_1D")
		)
		(pad "2" smd rect
			(at -0.2667 0)
			(size 0.3048 0.381)
			(layers "B.Cu" "B.Mask" "B.Paste")
			(net "SMB_RT_CPU1_P2_ROM_MUX_2D_R_SCL")
		)
	)
)
